# S9S_MB_2U (Grand Teton) — schematic netlist excerpt (pin names and nets, part order shuffled) for the footprints in the layout excerpt that follows; sources: Cadence DE-HDL packaged netlist, KiCad conversion of 03242023_DA0F0TMBIJ0_F0T_Motherboard_J_brd_V01_OCP.brd

R1019  Q_RES  0 5% EMPTY  pkg 0402LF  page 209 : A = CLK_25M_PCH_CPU1_DN ; B = CLK_25M_NSSC_CPU1_DN
R3162  Q_RES  4.7K 1% CHIP  pkg 0402LF  page 159 : A = P3V3_OCP_V3_2 ; B = OCP_V3_2_ID0

(kicad_pcb
	(version 20260206)
	(generator "pcbnew")
	(generator_version "10.0")
	(general
		(thickness 1.6)
		(legacy_teardrops no)
	)
	(paper "A4")
	(title_block
		(title "03242023_DA0F0TMBIJ0_F0T_Motherboard_J_brd_V01_OCP.brd")
		(comment 1 "Grand Teton / footprints 4273-4274 of 6105")
	)
	(layers
		(0 "F.Cu" signal "TOP")
		(4 "In1.Cu" signal "GND")
		(6 "In2.Cu" signal "IN1")
		(8 "In3.Cu" signal "GND1")
		(10 "In4.Cu" signal "IN2")
		(12 "In5.Cu" signal "GND2")
		(14 "In6.Cu" signal "IN3")
		(16 "In7.Cu" signal "GND3")
		(18 "In8.Cu" signal "VCC")
		(20 "In9.Cu" signal "VCC1")
		(22 "In10.Cu" signal "GND4")
		(24 "In11.Cu" signal "IN4")
		(26 "In12.Cu" signal "GND5")
		(28 "In13.Cu" signal "IN5")
		(30 "In14.Cu" signal "GND6")
		(32 "In15.Cu" signal "IN6")
		(34 "In16.Cu" signal "GND7")
		(2 "B.Cu" signal "BOTTOM")
		(9 "F.Adhes" user "F.Adhesive")
		(11 "B.Adhes" user "B.Adhesive")
		(13 "F.Paste" user "Package Geometry/Pastemask Top")
		(15 "B.Paste" user "Package Geometry/Pastemask Bottom")
		(5 "F.SilkS" user "Ref Des/Silkscreen Top")
		(7 "B.SilkS" user "Ref Des/Silkscreen Bottom")
		(1 "F.Mask" user "Board Geometry/Soldermask Top")
		(3 "B.Mask" user "Board Geometry/Soldermask Bottom")
		(17 "Dwgs.User" user "User.Drawings")
		(19 "Cmts.User" user "User.Comments")
		(21 "Eco1.User" user "User.Eco1")
		(23 "Eco2.User" user "User.Eco2")
		(25 "Edge.Cuts" user "Board Geometry/Outline")
		(27 "Margin" user)
		(31 "F.CrtYd" user "Package Geometry/Place Bound Top")
		(29 "B.CrtYd" user "Package Geometry/Place Bound Bottom")
		(35 "F.Fab" user "Ref Des/Assembly Top")
		(33 "B.Fab" user "Ref Des/Assembly Bottom")
	)
	(footprint ""
		(layer "B.Cu")
		(at 73.84288 -11.267948 -90)
		(property "Reference" "R3162"
			(at 0 0 90)
			(layer "B.SilkS")
			(hide yes)
			(effects
				(font
					(size 1.27 1.27)
				)
				(justify mirror)
			)
		)
		(property "Value" ""
			(at 0 0 90)
			(layer "B.Fab")
			(effects
				(font
					(size 1.27 1.27)
				)
				(justify mirror)
			)
		)
		(duplicate_pad_numbers_are_jumpers no)
		(fp_line
			(start -0.7874 0.4064)
			(end 0.7874 0.4064)
			(stroke
				(width 0.1524)
				(type default)
			)
			(layer "B.SilkS")
		)
		(fp_line
			(start 0.7874 0.4064)
			(end 0.7874 -0.4064)
			(stroke
				(width 0.1524)
				(type default)
			)
			(layer "B.SilkS")
		)
		(fp_line
			(start -0.7874 -0.4064)
			(end -0.7874 0.4064)
			(stroke
				(width 0.1524)
				(type default)
			)
			(layer "B.SilkS")
		)
		(fp_line
			(start 0.7874 -0.4064)
			(end -0.7874 -0.4064)
			(stroke
				(width 0.1524)
				(type default)
			)
			(layer "B.SilkS")
		)
		(fp_line
			(start -0.67945 0.3048)
			(end -0.120396 0.3048)
			(stroke
				(width 0.1)
				(type default)
			)
			(layer "B.Fab")
		)
		(fp_line
			(start -0.120396 0.3048)
			(end -0.120396 0.2794)
			(stroke
				(width 0.1)
				(type default)
			)
			(layer "B.Fab")
		)
		(fp_line
			(start 0.12065 0.3048)
			(end 0.67945 0.3048)
			(stroke
				(width 0.1)
				(type default)
			)
			(layer "B.Fab")
		)
		(fp_line
			(start 0.67945 0.3048)
			(end 0.67945 -0.305054)
			(stroke
				(width 0.1)
				(type default)
			)
			(layer "B.Fab")
		)
		(fp_line
			(start -0.120396 0.2794)
			(end 0.12065 0.2794)
			(stroke
				(width 0.1)
				(type default)
			)
			(layer "B.Fab")
		)
		(fp_line
			(start 0.12065 0.2794)
			(end 0.12065 0.3048)
			(stroke
				(width 0.1)
				(type default)
			)
			(layer "B.Fab")
		)
		(fp_line
			(start -0.12065 -0.2794)
			(end -0.12065 -0.3048)
			(stroke
				(width 0.1)
				(type default)
			)
			(layer "B.Fab")
		)
		(fp_line
			(start 0.12065 -0.2794)
			(end -0.12065 -0.2794)
			(stroke
				(width 0.1)
				(type default)
			)
			(layer "B.Fab")
		)
		(fp_line
			(start -0.67945 -0.3048)
			(end -0.67945 0.3048)
			(stroke
				(width 0.1)
				(type default)
			)
			(layer "B.Fab")
		)
		(fp_line
			(start -0.12065 -0.3048)
			(end -0.67945 -0.3048)
			(stroke
				(width 0.1)
				(type default)
			)
			(layer "B.Fab")
		)
		(fp_line
			(start 0.12065 -0.305054)
			(end 0.12065 -0.2794)
			(stroke
				(width 0.1)
				(type default)
			)
			(layer "B.Fab")
		)
		(fp_line
			(start 0.67945 -0.305054)
			(end 0.12065 -0.305054)
			(stroke
				(width 0.1)
				(type default)
			)
			(layer "B.Fab")
		)
		(pad "1" smd circle
			(at 0.40005 0 90)
			(size 0 0)
			(layers "B.Cu" "B.Mask" "B.Paste")
			(net "P3V3_OCP_V3_2")
		)
		(pad "2" smd circle
			(at -0.40005 0 90)
			(size 0 0)
			(layers "B.Cu" "B.Mask" "B.Paste")
			(net "OCP_V3_2_ID0")
		)
	)
	(footprint ""
		(layer "B.Cu")
		(at 237.001812 -135.401558)
		(property "Reference" "R1019"
			(at 0 0 0)
			(layer "B.SilkS")
			(hide yes)
			(effects
				(font
					(size 1.27 1.27)
				)
				(justify mirror)
			)
		)
		(property "Value" ""
			(at 0 0 0)
			(layer "B.Fab")
			(effects
				(font
					(size 1.27 1.27)
				)
				(justify mirror)
			)
		)
		(duplicate_pad_numbers_are_jumpers no)
		(fp_line
			(start -0.7874 -0.4064)
			(end -0.7874 0.4064)
			(stroke
				(width 0.1524)
				(type default)
			)
			(layer "B.SilkS")
		)
		(fp_line
			(start -0.7874 0.4064)
			(end -0.344932 0.4064)
			(stroke
				(width 0.1524)
				(type default)
			)
			(layer "B.SilkS")
		)
		(fp_line
			(start 0.305308 0.4064)
			(end 0.7874 0.4064)
			(stroke
				(width 0.1524)
				(type default)
			)
			(layer "B.SilkS")
		)
		(fp_line
			(start 0.7874 -0.4064)
			(end -0.7874 -0.4064)
			(stroke
				(width 0.1524)
				(type default)
			)
			(layer "B.SilkS")
		)
		(fp_line
			(start 0.7874 -0.19177)
			(end 0.7874 -0.4064)
			(stroke
				(width 0.1524)
				(type default)
			)
			(layer "B.SilkS")
		)
		(fp_line
			(start 0.7874 0.4064)
			(end 0.7874 0.21971)
			(stroke
				(width 0.1524)
				(type default)
			)
			(layer "B.SilkS")
		)
		(fp_line
			(start -0.67945 -0.3048)
			(end -0.67945 0.3048)
			(stroke
				(width 0.1)
				(type default)
			)
			(layer "B.Fab")
		)
		(fp_line
			(start -0.67945 0.3048)
			(end -0.120396 0.3048)
			(stroke
				(width 0.1)
				(type default)
			)
			(layer "B.Fab")
		)
		(fp_line
			(start -0.12065 -0.3048)
			(end -0.67945 -0.3048)
			(stroke
				(width 0.1)
				(type default)
			)
			(layer "B.Fab")
		)
		(fp_line
			(start -0.12065 -0.2794)
			(end -0.12065 -0.3048)
			(stroke
				(width 0.1)
				(type default)
			)
			(layer "B.Fab")
		)
		(fp_line
			(start -0.120396 0.2794)
			(end 0.12065 0.2794)
			(stroke
				(width 0.1)
				(type default)
			)
			(layer "B.Fab")
		)
		(fp_line
			(start -0.120396 0.3048)
			(end -0.120396 0.2794)
			(stroke
				(width 0.1)
				(type default)
			)
			(layer "B.Fab")
		)
		(fp_line
			(start 0.12065 -0.305054)
			(end 0.12065 -0.2794)
			(stroke
				(width 0.1)
				(type default)
			)
			(layer "B.Fab")
		)
		(fp_line
			(start 0.12065 -0.2794)
			(end -0.12065 -0.2794)
			(stroke
				(width 0.1)
				(type default)
			)
			(layer "B.Fab")
		)
		(fp_line
			(start 0.12065 0.2794)
			(end 0.12065 0.3048)
			(stroke
				(width 0.1)
				(type default)
			)
			(layer "B.Fab")
		)
		(fp_line
			(start 0.12065 0.3048)
			(end 0.67945 0.3048)
			(stroke
				(width 0.1)
				(type default)
			)
			(layer "B.Fab")
		)
		(fp_line
			(start 0.67945 -0.305054)
			(end 0.12065 -0.305054)
			(stroke
				(width 0.1)
				(type default)
			)
			(layer "B.Fab")
		)
		(fp_line
			(start 0.67945 0.3048)
			(end 0.67945 -0.305054)
			(stroke
				(width 0.1)
				(type default)
			)
			(layer "B.Fab")
		)
		(pad "1" smd rect
			(at 0.40005 0)
			(size 0.4572 0.508)
			(layers "B.Cu" "B.Mask" "B.Paste")
			(net "CLK_25M_PCH_CPU1_DN")
		)
		(pad "2" smd rect
			(at -0.40005 0)
			(size 0.4572 0.508)
			(layers "B.Cu" "B.Mask" "B.Paste")
			(net "CLK_25M_NSSC_CPU1_DN")
		)
	)
)
